# S9S_MB_2U (Grand Teton) — schematic netlist excerpt (pin names and nets, part order shuffled) for the footprints in the layout excerpt that follows; sources: Cadence DE-HDL packaged netlist, KiCad conversion of 03242023_DA0F0TMBIJ0_F0T_Motherboard_J_brd_V01_OCP.brd

C2383  Q_CAP  100NF 50V 10% EMPTY  pkg C0402  page 307 : A = P12V_AUX ; B = GND
R1259  Q_RES  10K 1% CHIP  pkg 0402LF  page 204 : A = P3V3_AUX ; B = PU_LPC_PME_N

(kicad_pcb
	(version 20260206)
	(generator "pcbnew")
	(generator_version "10.0")
	(general
		(thickness 1.6)
		(legacy_teardrops no)
	)
	(paper "A4")
	(title_block
		(title "03242023_DA0F0TMBIJ0_F0T_Motherboard_J_brd_V01_OCP.brd")
		(comment 1 "Grand Teton / footprints 2459-2460 of 6105")
	)
	(layers
		(0 "F.Cu" signal "TOP")
		(4 "In1.Cu" signal "GND")
		(6 "In2.Cu" signal "IN1")
		(8 "In3.Cu" signal "GND1")
		(10 "In4.Cu" signal "IN2")
		(12 "In5.Cu" signal "GND2")
		(14 "In6.Cu" signal "IN3")
		(16 "In7.Cu" signal "GND3")
		(18 "In8.Cu" signal "VCC")
		(20 "In9.Cu" signal "VCC1")
		(22 "In10.Cu" signal "GND4")
		(24 "In11.Cu" signal "IN4")
		(26 "In12.Cu" signal "GND5")
		(28 "In13.Cu" signal "IN5")
		(30 "In14.Cu" signal "GND6")
		(32 "In15.Cu" signal "IN6")
		(34 "In16.Cu" signal "GND7")
		(2 "B.Cu" signal "BOTTOM")
		(9 "F.Adhes" user "F.Adhesive")
		(11 "B.Adhes" user "B.Adhesive")
		(13 "F.Paste" user "Package Geometry/Pastemask Top")
		(15 "B.Paste" user "Package Geometry/Pastemask Bottom")
		(5 "F.SilkS" user "Ref Des/Silkscreen Top")
		(7 "B.SilkS" user "Ref Des/Silkscreen Bottom")
		(1 "F.Mask" user "Board Geometry/Soldermask Top")
		(3 "B.Mask" user "Board Geometry/Soldermask Bottom")
		(17 "Dwgs.User" user "User.Drawings")
		(19 "Cmts.User" user "User.Comments")
		(21 "Eco1.User" user "User.Eco1")
		(23 "Eco2.User" user "User.Eco2")
		(25 "Edge.Cuts" user "Board Geometry/Outline")
		(27 "Margin" user)
		(31 "F.CrtYd" user "Package Geometry/Place Bound Top")
		(29 "B.CrtYd" user "Package Geometry/Place Bound Bottom")
		(35 "F.Fab" user "Ref Des/Assembly Top")
		(33 "B.Fab" user "Ref Des/Assembly Bottom")
	)
	(footprint ""
		(layer "F.Cu")
		(at 312.443622 -43.932348)
		(property "Reference" "R1259"
			(at 0 0 0)
			(layer "F.SilkS")
			(hide yes)
			(effects
				(font
					(size 1.27 1.27)
				)
			)
		)
		(property "Value" ""
			(at 0 0 0)
			(layer "F.Fab")
			(effects
				(font
					(size 1.27 1.27)
				)
			)
		)
		(duplicate_pad_numbers_are_jumpers no)
		(fp_line
			(start -0.7874 -0.4064)
			(end 0.7874 -0.4064)
			(stroke
				(width 0.1524)
				(type default)
			)
			(layer "F.SilkS")
		)
		(fp_line
			(start -0.7874 0.4064)
			(end -0.7874 -0.4064)
			(stroke
				(width 0.1524)
				(type default)
			)
			(layer "F.SilkS")
		)
		(fp_line
			(start 0.7874 -0.4064)
			(end 0.7874 0.4064)
			(stroke
				(width 0.1524)
				(type default)
			)
			(layer "F.SilkS")
		)
		(fp_line
			(start 0.7874 0.4064)
			(end -0.7874 0.4064)
			(stroke
				(width 0.1524)
				(type default)
			)
			(layer "F.SilkS")
		)
		(fp_line
			(start -0.67945 -0.305054)
			(end -0.12065 -0.305054)
			(stroke
				(width 0.1)
				(type default)
			)
			(layer "F.Fab")
		)
		(fp_line
			(start -0.67945 0.3048)
			(end -0.67945 -0.305054)
			(stroke
				(width 0.1)
				(type default)
			)
			(layer "F.Fab")
		)
		(fp_line
			(start -0.12065 -0.305054)
			(end -0.12065 -0.2794)
			(stroke
				(width 0.1)
				(type default)
			)
			(layer "F.Fab")
		)
		(fp_line
			(start -0.12065 -0.2794)
			(end 0.12065 -0.2794)
			(stroke
				(width 0.1)
				(type default)
			)
			(layer "F.Fab")
		)
		(fp_line
			(start -0.12065 0.2794)
			(end -0.12065 0.3048)
			(stroke
				(width 0.1)
				(type default)
			)
			(layer "F.Fab")
		)
		(fp_line
			(start -0.12065 0.3048)
			(end -0.67945 0.3048)
			(stroke
				(width 0.1)
				(type default)
			)
			(layer "F.Fab")
		)
		(fp_line
			(start 0.120396 0.2794)
			(end -0.12065 0.2794)
			(stroke
				(width 0.1)
				(type default)
			)
			(layer "F.Fab")
		)
		(fp_line
			(start 0.120396 0.3048)
			(end 0.120396 0.2794)
			(stroke
				(width 0.1)
				(type default)
			)
			(layer "F.Fab")
		)
		(fp_line
			(start 0.12065 -0.3048)
			(end 0.67945 -0.3048)
			(stroke
				(width 0.1)
				(type default)
			)
			(layer "F.Fab")
		)
		(fp_line
			(start 0.12065 -0.2794)
			(end 0.12065 -0.3048)
			(stroke
				(width 0.1)
				(type default)
			)
			(layer "F.Fab")
		)
		(fp_line
			(start 0.67945 -0.3048)
			(end 0.67945 0.3048)
			(stroke
				(width 0.1)
				(type default)
			)
			(layer "F.Fab")
		)
		(fp_line
			(start 0.67945 0.3048)
			(end 0.120396 0.3048)
			(stroke
				(width 0.1)
				(type default)
			)
			(layer "F.Fab")
		)
		(pad "1" smd circle
			(at -0.40005 0)
			(size 0 0)
			(layers "F.Cu" "F.Mask" "F.Paste")
			(net "P3V3_AUX")
		)
		(pad "2" smd circle
			(at 0.40005 0)
			(size 0 0)
			(layers "F.Cu" "F.Mask" "F.Paste")
			(net "PU_LPC_PME_N")
		)
	)
	(footprint ""
		(layer "F.Cu")
		(at 200.533 -97.8662 180)
		(property "Reference" "C2383"
			(at 0 0 180)
			(layer "F.SilkS")
			(hide yes)
			(effects
				(font
					(size 1.27 1.27)
				)
			)
		)
		(property "Value" ""
			(at 0 0 180)
			(layer "F.Fab")
			(effects
				(font
					(size 1.27 1.27)
				)
			)
		)
		(duplicate_pad_numbers_are_jumpers no)
		(fp_line
			(start 0.7874 0.4064)
			(end -0.7874 0.4064)
			(stroke
				(width 0.1524)
				(type default)
			)
			(layer "F.SilkS")
		)
		(fp_line
			(start 0.7874 -0.4064)
			(end 0.7874 0.4064)
			(stroke
				(width 0.1524)
				(type default)
			)
			(layer "F.SilkS")
		)
		(fp_line
			(start -0.7874 0.4064)
			(end -0.7874 -0.4064)
			(stroke
				(width 0.1524)
				(type default)
			)
			(layer "F.SilkS")
		)
		(fp_line
			(start -0.7874 -0.4064)
			(end 0.7874 -0.4064)
			(stroke
				(width 0.1524)
				(type default)
			)
			(layer "F.SilkS")
		)
		(fp_line
			(start 0.67945 0.3048)
			(end 0.120396 0.3048)
			(stroke
				(width 0.1)
				(type default)
			)
			(layer "F.Fab")
		)
		(fp_line
			(start 0.67945 -0.3048)
			(end 0.67945 0.3048)
			(stroke
				(width 0.1)
				(type default)
			)
			(layer "F.Fab")
		)
		(fp_line
			(start 0.12065 -0.2794)
			(end 0.12065 -0.3048)
			(stroke
				(width 0.1)
				(type default)
			)
			(layer "F.Fab")
		)
		(fp_line
			(start 0.12065 -0.3048)
			(end 0.67945 -0.3048)
			(stroke
				(width 0.1)
				(type default)
			)
			(layer "F.Fab")
		)
		(fp_line
			(start 0.120396 0.3048)
			(end 0.120396 0.2794)
			(stroke
				(width 0.1)
				(type default)
			)
			(layer "F.Fab")
		)
		(fp_line
			(start 0.120396 0.2794)
			(end -0.12065 0.2794)
			(stroke
				(width 0.1)
				(type default)
			)
			(layer "F.Fab")
		)
		(fp_line
			(start -0.12065 0.3048)
			(end -0.67945 0.3048)
			(stroke
				(width 0.1)
				(type default)
			)
			(layer "F.Fab")
		)
		(fp_line
			(start -0.12065 0.2794)
			(end -0.12065 0.3048)
			(stroke
				(width 0.1)
				(type default)
			)
			(layer "F.Fab")
		)
		(fp_line
			(start -0.12065 -0.2794)
			(end 0.12065 -0.2794)
			(stroke
				(width 0.1)
				(type default)
			)
			(layer "F.Fab")
		)
		(fp_line
			(start -0.12065 -0.305054)
			(end -0.12065 -0.2794)
			(stroke
				(width 0.1)
				(type default)
			)
			(layer "F.Fab")
		)
		(fp_line
			(start -0.67945 0.3048)
			(end -0.67945 -0.305054)
			(stroke
				(width 0.1)
				(type default)
			)
			(layer "F.Fab")
		)
		(fp_line
			(start -0.67945 -0.305054)
			(end -0.12065 -0.305054)
			(stroke
				(width 0.1)
				(type default)
			)
			(layer "F.Fab")
		)
		(pad "1" smd circle
			(at -0.40005 0 180)
			(size 0 0)
			(layers "F.Cu" "F.Mask" "F.Paste")
			(net "P12V_AUX")
		)
		(pad "2" smd circle
			(at 0.40005 0 180)
			(size 0 0)
			(layers "F.Cu" "F.Mask" "F.Paste")
			(net "GND")
		)
	)
)
